(kicad_pcb
	(version 20260206)
	(generator "pcbnew")
	(generator_version "10.0")
	(general
		(thickness 1.6)
		(legacy_teardrops no)
	)
	(paper "A4")
	(title_block
		(title "Bryce Canyon_IOM_IOC_16318-2_OCP.brd")
		(comment 1 "Bryce Canyon / footprints 608-614 of 1605")
	)
	(layers
		(0 "F.Cu" signal "TOP")
		(4 "In1.Cu" signal "L2GND")
		(6 "In2.Cu" signal "L3")
		(8 "In3.Cu" signal "L4VCC")
		(10 "In4.Cu" signal "L5VCC")
		(12 "In5.Cu" signal "L6")
		(14 "In6.Cu" signal "L7GND")
		(2 "B.Cu" signal "BOTTOM")
		(9 "F.Adhes" user "F.Adhesive")
		(11 "B.Adhes" user "B.Adhesive")
		(13 "F.Paste" user "Package Geometry/Pastemask Top")
		(15 "B.Paste" user "Package Geometry/Pastemask Bottom")
		(5 "F.SilkS" user "Ref Des/Silkscreen Top")
		(7 "B.SilkS" user "Ref Des/Silkscreen Bottom")
		(1 "F.Mask" user "Board Geometry/Soldermask Top")
		(3 "B.Mask" user "Board Geometry/Soldermask Bottom")
		(17 "Dwgs.User" user "User.Drawings")
		(19 "Cmts.User" user "User.Comments")
		(21 "Eco1.User" user "User.Eco1")
		(23 "Eco2.User" user "User.Eco2")
		(25 "Edge.Cuts" user "Board Geometry/Outline")
		(27 "Margin" user)
		(31 "F.CrtYd" user "Package Geometry/Place Bound Top")
		(29 "B.CrtYd" user "Package Geometry/Place Bound Bottom")
		(35 "F.Fab" user "Ref Des/Assembly Top")
		(33 "B.Fab" user "Ref Des/Assembly Bottom")
	)
	(footprint ""
		(layer "F.Cu")
		(at 179.3748 -141.8082 -90)
		(property "Reference" "C161"
			(at 0 0 270)
			(layer "F.SilkS")
			(hide yes)
			(effects
				(font
					(size 1.27 1.27)
				)
			)
		)
		(property "Value" "SC1U16V3KX-5GP"
			(at 0 -2.8194 270)
			(unlocked yes)
			(layer "F.Fab")
			(hide yes)
			(effects
				(font
					(size 1.016 1.016)
					(thickness 0.1524)
				)
			)
		)
		(property "Device Type" "C603H36"
			(at 0 -4.3434 270)
			(unlocked yes)
			(layer "F.Fab")
			(hide yes)
			(effects
				(font
					(size 1.016 1.016)
					(thickness 0.1524)
				)
			)
		)
		(duplicate_pad_numbers_are_jumpers no)
		(fp_line
			(start 0.508 0)
			(end -0.508 0)
			(stroke
				(width 0.2032)
				(type default)
			)
			(layer "F.SilkS")
		)
		(fp_rect
			(start -0.5842 1.3335)
			(end 0.5842 -1.3335)
			(stroke
				(width 0)
				(type default)
			)
			(fill no)
			(layer "F.CrtYd")
		)
		(fp_rect
			(start -0.5842 1.3335)
			(end 0.5842 -1.3335)
			(stroke
				(width 0)
				(type default)
			)
			(fill no)
			(layer "F.Fab")
		)
		(pad "1" smd custom
			(at 0 -0.762 270)
			(size 0.2159 0.2159)
			(layers "F.Cu" "F.Mask" "F.Paste")
			(net "GND")
			(options
				(clearance outline)
				(anchor circle)
			)
			(primitives
				(gr_poly
					(pts
						(arc
							(start -0.3302 -0.4318)
							(mid -0.402042 -0.402042)
							(end -0.4318 -0.3302)
						)
						(arc
							(start -0.4318 0.3302)
							(mid -0.402042 0.402042)
							(end -0.3302 0.4318)
						)
						(arc
							(start 0.3302 0.4318)
							(mid 0.402042 0.402042)
							(end 0.4318 0.3302)
						)
						(arc
							(start 0.4318 -0.3302)
							(mid 0.402042 -0.402042)
							(end 0.3302 -0.4318)
						)
					)
					(width 0)
					(fill yes)
				)
			)
		)
		(pad "2" smd custom
			(at 0 0.762 270)
			(size 0.2159 0.2159)
			(layers "F.Cu" "F.Mask" "F.Paste")
			(net "P5V_STBY_VREG")
			(options
				(clearance outline)
				(anchor circle)
			)
			(primitives
				(gr_poly
					(pts
						(arc
							(start -0.3302 -0.4318)
							(mid -0.402042 -0.402042)
							(end -0.4318 -0.3302)
						)
						(arc
							(start -0.4318 0.3302)
							(mid -0.402042 0.402042)
							(end -0.3302 0.4318)
						)
						(arc
							(start 0.3302 0.4318)
							(mid 0.402042 0.402042)
							(end 0.4318 0.3302)
						)
						(arc
							(start 0.4318 -0.3302)
							(mid 0.402042 -0.402042)
							(end 0.3302 -0.4318)
						)
					)
					(width 0)
					(fill yes)
				)
			)
		)
	)
	(footprint ""
		(layer "F.Cu")
		(at 19.144742 -129.077466 180)
		(property "Reference" "R215"
			(at 0 0 180)
			(layer "F.SilkS")
			(hide yes)
			(effects
				(font
					(size 1.27 1.27)
				)
			)
		)
		(property "Value" "120R2F-GP"
			(at 0.064008 -3.993896 180)
			(unlocked yes)
			(layer "F.Fab")
			(hide yes)
			(effects
				(font
					(size 1.016 1.016)
					(thickness 0.1524)
				)
			)
		)
		(property "Device Type" "R402H16"
			(at 0.064008 -5.517896 180)
			(unlocked yes)
			(layer "F.Fab")
			(hide yes)
			(effects
				(font
					(size 1.016 1.016)
					(thickness 0.1524)
				)
			)
		)
		(duplicate_pad_numbers_are_jumpers no)
		(fp_line
			(start 0.508 -0.9398)
			(end -0.508 -0.9398)
			(stroke
				(width 0.1524)
				(type default)
			)
			(layer "F.SilkS")
		)
		(fp_line
			(start -0.508 -0.9398)
			(end -0.508 0.9398)
			(stroke
				(width 0.1524)
				(type default)
			)
			(layer "F.SilkS")
		)
		(fp_rect
			(start -0.508 0.9398)
			(end 0.508 -0.9398)
			(stroke
				(width 0)
				(type default)
			)
			(fill no)
			(layer "F.CrtYd")
		)
		(fp_rect
			(start -0.508 0.9398)
			(end 0.508 -0.9398)
			(stroke
				(width 0)
				(type default)
			)
			(fill no)
			(layer "F.Fab")
		)
		(pad "1" smd custom
			(at 0 -0.4445 180)
			(size 0.1397 0.1397)
			(layers "F.Cu" "F.Mask" "F.Paste")
			(net "GND")
			(options
				(clearance outline)
				(anchor circle)
			)
			(primitives
				(gr_poly
					(pts
						(arc
							(start -0.1778 -0.2794)
							(mid -0.249642 -0.249642)
							(end -0.2794 -0.1778)
						)
						(arc
							(start -0.2794 0.1778)
							(mid -0.249642 0.249642)
							(end -0.1778 0.2794)
						)
						(arc
							(start 0.1778 0.2794)
							(mid 0.249642 0.249642)
							(end 0.2794 0.1778)
						)
						(arc
							(start 0.2794 -0.1778)
							(mid 0.249642 -0.249642)
							(end 0.1778 -0.2794)
						)
					)
					(width 0)
					(fill yes)
				)
			)
		)
		(pad "2" smd custom
			(at 0 0.4445 180)
			(size 0.1397 0.1397)
			(layers "F.Cu" "F.Mask" "F.Paste")
			(net "MEMCSN")
			(options
				(clearance outline)
				(anchor circle)
			)
			(primitives
				(gr_poly
					(pts
						(arc
							(start -0.1778 -0.2794)
							(mid -0.249642 -0.249642)
							(end -0.2794 -0.1778)
						)
						(arc
							(start -0.2794 0.1778)
							(mid -0.249642 0.249642)
							(end -0.1778 0.2794)
						)
						(arc
							(start 0.1778 0.2794)
							(mid 0.249642 0.249642)
							(end 0.2794 0.1778)
						)
						(arc
							(start 0.2794 -0.1778)
							(mid 0.249642 -0.249642)
							(end 0.1778 -0.2794)
						)
					)
					(width 0)
					(fill yes)
				)
			)
		)
	)
	(footprint ""
		(layer "F.Cu")
		(at 115.2652 -14.9098 180)
		(property "Reference" "C128"
			(at 0 0 180)
			(layer "F.SilkS")
			(hide yes)
			(effects
				(font
					(size 1.27 1.27)
				)
			)
		)
		(property "Value" "SC1U25V3KX-GP"
			(at 0 -2.8194 180)
			(unlocked yes)
			(layer "F.Fab")
			(hide yes)
			(effects
				(font
					(size 1.016 1.016)
					(thickness 0.1524)
				)
			)
		)
		(property "Device Type" "C603H36"
			(at 0 -4.3434 180)
			(unlocked yes)
			(layer "F.Fab")
			(hide yes)
			(effects
				(font
					(size 1.016 1.016)
					(thickness 0.1524)
				)
			)
		)
		(duplicate_pad_numbers_are_jumpers no)
		(fp_line
			(start 0.508 0)
			(end -0.508 0)
			(stroke
				(width 0.2032)
				(type default)
			)
			(layer "F.SilkS")
		)
		(fp_rect
			(start -0.5842 1.3335)
			(end 0.5842 -1.3335)
			(stroke
				(width 0)
				(type default)
			)
			(fill no)
			(layer "F.CrtYd")
		)
		(fp_rect
			(start -0.5842 1.3335)
			(end 0.5842 -1.3335)
			(stroke
				(width 0)
				(type default)
			)
			(fill no)
			(layer "F.Fab")
		)
		(pad "1" smd custom
			(at 0 -0.762 180)
			(size 0.2159 0.2159)
			(layers "F.Cu" "F.Mask" "F.Paste")
			(net "MB0_VCC")
			(options
				(clearance outline)
				(anchor circle)
			)
			(primitives
				(gr_poly
					(pts
						(arc
							(start -0.3302 -0.4318)
							(mid -0.402042 -0.402042)
							(end -0.4318 -0.3302)
						)
						(arc
							(start -0.4318 0.3302)
							(mid -0.402042 0.402042)
							(end -0.3302 0.4318)
						)
						(arc
							(start 0.3302 0.4318)
							(mid 0.402042 0.402042)
							(end 0.4318 0.3302)
						)
						(arc
							(start 0.4318 -0.3302)
							(mid 0.402042 -0.402042)
							(end 0.3302 -0.4318)
						)
					)
					(width 0)
					(fill yes)
				)
			)
		)
		(pad "2" smd custom
			(at 0 0.762 180)
			(size 0.2159 0.2159)
			(layers "F.Cu" "F.Mask" "F.Paste")
			(net "AGND_CURRENT_MON")
			(options
				(clearance outline)
				(anchor circle)
			)
			(primitives
				(gr_poly
					(pts
						(arc
							(start -0.3302 -0.4318)
							(mid -0.402042 -0.402042)
							(end -0.4318 -0.3302)
						)
						(arc
							(start -0.4318 0.3302)
							(mid -0.402042 0.402042)
							(end -0.3302 0.4318)
						)
						(arc
							(start 0.3302 0.4318)
							(mid 0.402042 0.402042)
							(end 0.4318 0.3302)
						)
						(arc
							(start 0.4318 -0.3302)
							(mid 0.402042 -0.402042)
							(end 0.3302 -0.4318)
						)
					)
					(width 0)
					(fill yes)
				)
			)
		)
	)
	(footprint ""
		(layer "F.Cu")
		(at 41.744646 -177.06721)
		(property "Reference" "R485"
			(at 0 0 0)
			(layer "F.SilkS")
			(hide yes)
			(effects
				(font
					(size 1.27 1.27)
				)
			)
		)
		(property "Value" "0R2J-2-GP"
			(at 0.064008 -3.993896 0)
			(unlocked yes)
			(layer "F.Fab")
			(hide yes)
			(effects
				(font
					(size 1.016 1.016)
					(thickness 0.1524)
				)
			)
		)
		(property "Device Type" "R402H16"
			(at 0.064008 -5.517896 0)
			(unlocked yes)
			(layer "F.Fab")
			(hide yes)
			(effects
				(font
					(size 1.016 1.016)
					(thickness 0.1524)
				)
			)
		)
		(duplicate_pad_numbers_are_jumpers no)
		(fp_line
			(start -0.508 -0.9398)
			(end -0.508 0.9398)
			(stroke
				(width 0.1524)
				(type default)
			)
			(layer "F.SilkS")
		)
		(fp_line
			(start 0.508 -0.9398)
			(end -0.508 -0.9398)
			(stroke
				(width 0.1524)
				(type default)
			)
			(layer "F.SilkS")
		)
		(fp_rect
			(start -0.508 0.9398)
			(end 0.508 -0.9398)
			(stroke
				(width 0)
				(type default)
			)
			(fill no)
			(layer "F.CrtYd")
		)
		(fp_rect
			(start -0.508 0.9398)
			(end 0.508 -0.9398)
			(stroke
				(width 0)
				(type default)
			)
			(fill no)
			(layer "F.Fab")
		)
		(pad "1" smd custom
			(at 0 -0.4445)
			(size 0.1397 0.1397)
			(layers "F.Cu" "F.Mask" "F.Paste")
			(net "P3V3_STBY_EN")
			(options
				(clearance outline)
				(anchor circle)
			)
			(primitives
				(gr_poly
					(pts
						(arc
							(start -0.1778 -0.2794)
							(mid -0.249642 -0.249642)
							(end -0.2794 -0.1778)
						)
						(arc
							(start -0.2794 0.1778)
							(mid -0.249642 0.249642)
							(end -0.1778 0.2794)
						)
						(arc
							(start 0.1778 0.2794)
							(mid 0.249642 0.249642)
							(end 0.2794 0.1778)
						)
						(arc
							(start 0.2794 -0.1778)
							(mid 0.249642 -0.249642)
							(end 0.1778 -0.2794)
						)
					)
					(width 0)
					(fill yes)
				)
			)
		)
		(pad "2" smd custom
			(at 0 0.4445)
			(size 0.1397 0.1397)
			(layers "F.Cu" "F.Mask" "F.Paste")
			(net "PWRGD_P5V_STBY")
			(options
				(clearance outline)
				(anchor circle)
			)
			(primitives
				(gr_poly
					(pts
						(arc
							(start -0.1778 -0.2794)
							(mid -0.249642 -0.249642)
							(end -0.2794 -0.1778)
						)
						(arc
							(start -0.2794 0.1778)
							(mid -0.249642 0.249642)
							(end -0.1778 0.2794)
						)
						(arc
							(start 0.1778 0.2794)
							(mid 0.249642 0.249642)
							(end 0.2794 0.1778)
						)
						(arc
							(start 0.2794 -0.1778)
							(mid 0.249642 -0.249642)
							(end 0.1778 -0.2794)
						)
					)
					(width 0)
					(fill yes)
				)
			)
		)
	)
	(footprint ""
		(layer "F.Cu")
		(at 92.623894 -164.807646 180)
		(property "Reference" "X1"
			(at 0 0 180)
			(layer "F.SilkS")
			(hide yes)
			(effects
				(font
					(size 1.27 1.27)
				)
			)
		)
		(property "Value" "XTAL-24MHZ-87-GP"
			(at -0.0889 -3.0988 180)
			(unlocked yes)
			(layer "F.Fab")
			(hide yes)
			(effects
				(font
					(size 1.016 1.016)
					(thickness 0.1524)
				)
			)
		)
		(property "Device Type" "OSC-3225-4P-4H30"
			(at -0.0889 -4.6228 180)
			(unlocked yes)
			(layer "F.Fab")
			(hide yes)
			(effects
				(font
					(size 1.016 1.016)
					(thickness 0.1524)
				)
			)
		)
		(duplicate_pad_numbers_are_jumpers no)
		(fp_line
			(start 2.1209 1.5494)
			(end 2.1209 -1.5494)
			(stroke
				(width 0.1524)
				(type default)
			)
			(layer "F.SilkS")
		)
		(fp_line
			(start 2.1209 -1.5494)
			(end -2.1209 -1.5494)
			(stroke
				(width 0.1524)
				(type default)
			)
			(layer "F.SilkS")
		)
		(fp_line
			(start -1.143 1.651)
			(end -2.2098 1.651)
			(stroke
				(width 0.3302)
				(type default)
			)
			(layer "F.SilkS")
		)
		(fp_line
			(start -2.1209 1.5494)
			(end 2.1209 1.5494)
			(stroke
				(width 0.1524)
				(type default)
			)
			(layer "F.SilkS")
		)
		(fp_line
			(start -2.1209 -1.5494)
			(end -2.1209 1.5494)
			(stroke
				(width 0.1524)
				(type default)
			)
			(layer "F.SilkS")
		)
		(fp_line
			(start -2.2098 1.651)
			(end -2.2098 0.6604)
			(stroke
				(width 0.3302)
				(type default)
			)
			(layer "F.SilkS")
		)
		(fp_poly
			(pts
				(xy -2.6289 1.1938) (xy -2.6289 0.3302) (xy -2.1971 0.762)
			)
			(stroke
				(width 0)
				(type default)
			)
			(fill yes)
			(layer "F.SilkS")
		)
		(fp_rect
			(start -1.6002 1.2446)
			(end 1.6002 -1.2446)
			(stroke
				(width 0)
				(type default)
			)
			(fill no)
			(layer "F.CrtYd")
		)
		(fp_poly
			(pts
				(xy -2.3749 1.8034) (xy -2.3749 -1.8034) (xy 2.3749 -1.8034) (xy 2.3749 1.8034) (xy 0.00254 1.8034)
				(xy 0.00254 1.2446) (xy 1.6002 1.2446) (xy 1.6002 -1.2446) (xy -1.6002 -1.2446) (xy -1.6002 1.2446)
				(xy -0.00254 1.2446) (xy -0.00254 1.8034)
			)
			(stroke
				(width 0)
				(type default)
			)
			(fill no)
			(layer "F.CrtYd")
		)
		(fp_rect
			(start -2.3749 1.8034)
			(end 2.3749 -1.8034)
			(stroke
				(width 0)
				(type default)
			)
			(fill no)
			(layer "F.Fab")
		)
		(pad "1" smd rect
			(at -1.171448 0.756412 180)
			(size 1.397 1.0668)
			(layers "F.Cu" "F.Mask" "F.Paste")
			(net "USB_HUB_XTAL_OUT")
		)
		(pad "2" smd rect
			(at 1.171448 0.756412 180)
			(size 1.397 1.0668)
			(layers "F.Cu" "F.Mask" "F.Paste")
			(net "GND")
		)
		(pad "3" smd rect
			(at 1.171448 -0.756412 180)
			(size 1.397 1.0668)
			(layers "F.Cu" "F.Mask" "F.Paste")
			(net "USB_HUB_XTAL_IN")
		)
		(pad "4" smd rect
			(at -1.171448 -0.756412 180)
			(size 1.397 1.0668)
			(layers "F.Cu" "F.Mask" "F.Paste")
			(net "GND")
		)
		(zone
			(layer "F.Cu")
			(hatch none 0.5)
			(connect_pads
				(clearance 0)
			)
			(min_thickness 0.25)
			(keepout
				(tracks not_allowed)
				(vias allowed)
				(pads allowed)
				(copperpour not_allowed)
				(footprints allowed)
			)
			(placement
				(enabled no)
				(sheetname "")
			)
			(fill
				(thermal_gap 0.5)
				(thermal_bridge_width 0.5)
				(island_removal_mode 0)
			)
			(polygon
				(pts
					(xy 92.674694 -164.858446) (xy 92.573094 -164.858446) (xy 92.573094 -164.756846) (xy 92.674694 -164.756846)
				)
			)
		)
		(zone
			(layer "F.Cu")
			(hatch none 0.5)
			(connect_pads
				(clearance 0)
			)
			(min_thickness 0.25)
			(keepout
				(tracks allowed)
				(vias not_allowed)
				(pads allowed)
				(copperpour not_allowed)
				(footprints allowed)
			)
			(placement
				(enabled no)
				(sheetname "")
			)
			(fill
				(thermal_gap 0.5)
				(thermal_bridge_width 0.5)
				(island_removal_mode 0)
			)
			(polygon
				(pts
					(xy 93.096842 -163.517834) (xy 92.150946 -163.517834) (xy 92.150946 -164.584634) (xy 90.753946 -164.584634)
					(xy 90.753946 -165.030658) (xy 92.150946 -165.030658) (xy 92.150946 -166.097458) (xy 93.096842 -166.097458)
					(xy 93.096842 -165.030658) (xy 94.493842 -165.030658) (xy 94.493842 -164.584634) (xy 93.096842 -164.584634)
				)
			)
		)
	)
	(footprint ""
		(layer "F.Cu")
		(at 21.2725 -167.247316 180)
		(property "Reference" "C223"
			(at 0 0 180)
			(layer "F.SilkS")
			(hide yes)
			(effects
				(font
					(size 1.27 1.27)
				)
			)
		)
		(property "Value" "SC10U6D3V5KX-4GP"
			(at -0.0762 -6.1214 180)
			(unlocked yes)
			(layer "F.Fab")
			(hide yes)
			(effects
				(font
					(size 1.016 1.016)
					(thickness 0.1524)
				)
			)
		)
		(property "Device Type" "C805H58"
			(at -0.0762 -8.1534 180)
			(unlocked yes)
			(layer "F.Fab")
			(hide yes)
			(effects
				(font
					(size 1.016 1.016)
					(thickness 0.1524)
				)
			)
		)
		(duplicate_pad_numbers_are_jumpers no)
		(fp_line
			(start 0.635 0)
			(end -0.635 0)
			(stroke
				(width 0.508)
				(type default)
			)
			(layer "F.SilkS")
		)
		(fp_rect
			(start -0.9652 1.778)
			(end 0.9652 -1.778)
			(stroke
				(width 0)
				(type default)
			)
			(fill no)
			(layer "F.CrtYd")
		)
		(fp_poly
			(pts
				(xy -0.9652 -1.778) (xy 0.9652 -1.778) (xy 0.9652 1.778) (xy -0.9652 1.778)
			)
			(stroke
				(width 0)
				(type default)
			)
			(fill no)
			(layer "F.Fab")
		)
		(pad "1" smd rect
			(at 0 -0.9652 180)
			(size 1.397 1.143)
			(layers "F.Cu" "F.Mask" "F.Paste")
			(net "TPS74801_P1V2_STBY_OUT")
		)
		(pad "2" smd rect
			(at 0 0.9652 180)
			(size 1.397 1.143)
			(layers "F.Cu" "F.Mask" "F.Paste")
			(net "GND")
		)
	)
	(footprint ""
		(layer "F.Cu")
		(at 169.799 -180.2892 90)
		(property "Reference" "G1"
			(at 0 0 90)
			(layer "F.SilkS")
			(hide yes)
			(effects
				(font
					(size 1.27 1.27)
				)
			)
		)
		(property "Value" "GAP-CLOSE-PWR-4-GP"
			(at -2.4638 -0.5461 90)
			(unlocked yes)
			(layer "F.Fab")
			(hide yes)
			(effects
				(font
					(size 1.016 1.016)
					(thickness 0.1524)
				)
			)
		)
		(property "Device Type" "GAP-CLOSE-PWR-4"
			(at -2.4638 -2.0701 90)
			(unlocked yes)
			(layer "F.Fab")
			(hide yes)
			(effects
				(font
					(size 1.016 1.016)
					(thickness 0.1524)
				)
			)
		)
		(duplicate_pad_numbers_are_jumpers no)
		(fp_rect
			(start -0.2794 0.254)
			(end 0.2794 -0.254)
			(stroke
				(width 0)
				(type default)
			)
			(fill no)
			(layer "F.CrtYd")
		)
		(fp_rect
			(start -0.2794 0.254)
			(end 0.2794 -0.254)
			(stroke
				(width 0)
				(type default)
			)
			(fill no)
			(layer "F.Fab")
		)
		(pad "1" smd rect
			(at -0.0635 0 90)
			(size 0.1778 0.254)
			(layers "F.Cu" "F.Mask" "F.Paste")
			(net "P5V_STBY")
		)
		(pad "2" smd rect
			(at 0.0635 0 90)
			(size 0.1778 0.254)
			(layers "F.Cu" "F.Mask" "F.Paste")
			(net "P5V_CC")
		)
	)
)
